(kicad_pcb
	(version 20260206)
	(generator "pcbnew")
	(generator_version "10.0")
	(general
		(thickness 1.6)
		(legacy_teardrops no)
	)
	(paper "A4")
	(title_block
		(title "Bryce Canyon_SCC_16316-1_OCP.brd")
		(comment 1 "Bryce Canyon / footprint 146 of 1561 (CN2), pads 301-342 of 342")
	)
	(layers
		(0 "F.Cu" signal "TOP")
		(4 "In1.Cu" signal "L2GND")
		(6 "In2.Cu" signal "L3")
		(8 "In3.Cu" signal "L4VCC")
		(10 "In4.Cu" signal "L5VCC")
		(12 "In5.Cu" signal "L6")
		(14 "In6.Cu" signal "L7GND")
		(2 "B.Cu" signal "BOTTOM")
		(9 "F.Adhes" user "F.Adhesive")
		(11 "B.Adhes" user "B.Adhesive")
		(13 "F.Paste" user "Package Geometry/Pastemask Top")
		(15 "B.Paste" user "Package Geometry/Pastemask Bottom")
		(5 "F.SilkS" user "Ref Des/Silkscreen Top")
		(7 "B.SilkS" user "Ref Des/Silkscreen Bottom")
		(1 "F.Mask" user "Board Geometry/Soldermask Top")
		(3 "B.Mask" user "Board Geometry/Soldermask Bottom")
		(17 "Dwgs.User" user "User.Drawings")
		(19 "Cmts.User" user "User.Comments")
		(21 "Eco1.User" user "User.Eco1")
		(23 "Eco2.User" user "User.Eco2")
		(25 "Edge.Cuts" user "Board Geometry/Outline")
		(27 "Margin" user)
		(31 "F.CrtYd" user "Package Geometry/Place Bound Top")
		(29 "B.CrtYd" user "Package Geometry/Place Bound Bottom")
		(35 "F.Fab" user "Ref Des/Assembly Top")
		(33 "B.Fab" user "Ref Des/Assembly Bottom")
	)
	(footprint ""
		(layer "F.Cu")
		(at 86.000082 -3.800094)
		(property "Reference" "CN2"
			(at 0 0 0)
			(layer "F.SilkS")
			(hide yes)
			(effects
				(font
					(size 1.27 1.27)
				)
			)
		)
		(property "Value" "AMP-CONN342-10R-3-GP"
			(at -12.8905 -12.5222 0)
			(unlocked yes)
			(layer "F.Fab")
			(hide yes)
			(effects
				(font
					(size 1.016 1.016)
					(thickness 0.1524)
				)
			)
		)
		(property "Device Type" "PREFIT-342P-648260H400"
			(at -12.8905 -14.0462 0)
			(unlocked yes)
			(layer "F.Fab")
			(hide yes)
			(effects
				(font
					(size 1.016 1.016)
					(thickness 0.1524)
				)
			)
		)
		(duplicate_pad_numbers_are_jumpers no)
		(pad "GND85" thru_hole circle
			(at 43.200066 -2.500122)
			(size 0.762 0.762)
			(drill 0.359918)
			(layers "*.Cu" "*.Mask")
			(remove_unused_layers no)
			(net "GND")
			(clearance 0.1651)
			(thermal_gap 0.1651)
		)
		(pad "GND86" thru_hole circle
			(at 43.200066 -6.100064)
			(size 0.762 0.762)
			(drill 0.359918)
			(layers "*.Cu" "*.Mask")
			(remove_unused_layers no)
			(net "GND")
			(clearance 0.1651)
			(thermal_gap 0.1651)
		)
		(pad "GND87" thru_hole circle
			(at 43.200066 -9.700006)
			(size 0.762 0.762)
			(drill 0.359918)
			(layers "*.Cu" "*.Mask")
			(remove_unused_layers no)
			(net "GND")
			(clearance 0.1651)
			(thermal_gap 0.1651)
		)
		(pad "GND88" thru_hole circle
			(at 44.99991 2.29997)
			(size 0.762 0.762)
			(drill 0.359918)
			(layers "*.Cu" "*.Mask")
			(remove_unused_layers no)
			(net "GND")
			(clearance 0.1651)
			(thermal_gap 0.1651)
		)
		(pad "GND89" thru_hole circle
			(at 44.99991 -1.299972)
			(size 0.762 0.762)
			(drill 0.359918)
			(layers "*.Cu" "*.Mask")
			(remove_unused_layers no)
			(net "GND")
			(clearance 0.1651)
			(thermal_gap 0.1651)
		)
		(pad "GND90" thru_hole circle
			(at 44.99991 -4.899914)
			(size 0.762 0.762)
			(drill 0.359918)
			(layers "*.Cu" "*.Mask")
			(remove_unused_layers no)
			(net "GND")
			(clearance 0.1651)
			(thermal_gap 0.1651)
		)
		(pad "GND91" thru_hole circle
			(at 44.99991 -8.50011)
			(size 0.762 0.762)
			(drill 0.359918)
			(layers "*.Cu" "*.Mask")
			(remove_unused_layers no)
			(net "GND")
			(clearance 0.1651)
			(thermal_gap 0.1651)
		)
		(pad "GND92" thru_hole circle
			(at 46.800008 -2.500122)
			(size 0.762 0.762)
			(drill 0.359918)
			(layers "*.Cu" "*.Mask")
			(remove_unused_layers no)
			(net "GND")
			(clearance 0.1651)
			(thermal_gap 0.1651)
		)
		(pad "GND93" thru_hole circle
			(at 46.800008 -6.100064)
			(size 0.762 0.762)
			(drill 0.359918)
			(layers "*.Cu" "*.Mask")
			(remove_unused_layers no)
			(net "GND")
			(clearance 0.1651)
			(thermal_gap 0.1651)
		)
		(pad "GND94" thru_hole circle
			(at 46.800008 -9.700006)
			(size 0.762 0.762)
			(drill 0.359918)
			(layers "*.Cu" "*.Mask")
			(remove_unused_layers no)
			(net "GND")
			(clearance 0.1651)
			(thermal_gap 0.1651)
		)
		(pad "GND95" thru_hole circle
			(at 48.600106 2.29997)
			(size 0.762 0.762)
			(drill 0.359918)
			(layers "*.Cu" "*.Mask")
			(remove_unused_layers no)
			(net "GND")
			(clearance 0.1651)
			(thermal_gap 0.1651)
		)
		(pad "GND96" thru_hole circle
			(at 48.600106 -1.299972)
			(size 0.762 0.762)
			(drill 0.359918)
			(layers "*.Cu" "*.Mask")
			(remove_unused_layers no)
			(net "GND")
			(clearance 0.1651)
			(thermal_gap 0.1651)
		)
		(pad "GND97" thru_hole circle
			(at 48.600106 -4.899914)
			(size 0.762 0.762)
			(drill 0.359918)
			(layers "*.Cu" "*.Mask")
			(remove_unused_layers no)
			(net "GND")
			(clearance 0.1651)
			(thermal_gap 0.1651)
		)
		(pad "GND98" thru_hole circle
			(at 48.600106 -8.50011)
			(size 0.762 0.762)
			(drill 0.359918)
			(layers "*.Cu" "*.Mask")
			(remove_unused_layers no)
			(net "GND")
			(clearance 0.1651)
			(thermal_gap 0.1651)
		)
		(pad "GND99" thru_hole circle
			(at 50.39995 -2.500122)
			(size 0.762 0.762)
			(drill 0.359918)
			(layers "*.Cu" "*.Mask")
			(remove_unused_layers no)
			(net "GND")
			(clearance 0.1651)
			(thermal_gap 0.1651)
		)
		(pad "GND100" thru_hole circle
			(at 50.39995 -6.100064)
			(size 0.762 0.762)
			(drill 0.359918)
			(layers "*.Cu" "*.Mask")
			(remove_unused_layers no)
			(net "GND")
			(clearance 0.1651)
			(thermal_gap 0.1651)
		)
		(pad "GND101" thru_hole circle
			(at 50.39995 -9.700006)
			(size 0.762 0.762)
			(drill 0.359918)
			(layers "*.Cu" "*.Mask")
			(remove_unused_layers no)
			(net "GND")
			(clearance 0.1651)
			(thermal_gap 0.1651)
		)
		(pad "GND102" thru_hole circle
			(at 52.200048 2.29997)
			(size 0.762 0.762)
			(drill 0.359918)
			(layers "*.Cu" "*.Mask")
			(remove_unused_layers no)
			(net "GND")
			(clearance 0.1651)
			(thermal_gap 0.1651)
		)
		(pad "GND103" thru_hole circle
			(at 52.200048 -1.299972)
			(size 0.762 0.762)
			(drill 0.359918)
			(layers "*.Cu" "*.Mask")
			(remove_unused_layers no)
			(net "GND")
			(clearance 0.1651)
			(thermal_gap 0.1651)
		)
		(pad "GND104" thru_hole circle
			(at 52.200048 -4.899914)
			(size 0.762 0.762)
			(drill 0.359918)
			(layers "*.Cu" "*.Mask")
			(remove_unused_layers no)
			(net "GND")
			(clearance 0.1651)
			(thermal_gap 0.1651)
		)
		(pad "GND105" thru_hole circle
			(at 52.200048 -8.50011)
			(size 0.762 0.762)
			(drill 0.359918)
			(layers "*.Cu" "*.Mask")
			(remove_unused_layers no)
			(net "GND")
			(clearance 0.1651)
			(thermal_gap 0.1651)
		)
		(pad "GND106" thru_hole circle
			(at 53.999892 -2.500122)
			(size 0.762 0.762)
			(drill 0.359918)
			(layers "*.Cu" "*.Mask")
			(remove_unused_layers no)
			(net "GND")
			(clearance 0.1651)
			(thermal_gap 0.1651)
		)
		(pad "GND107" thru_hole circle
			(at 53.999892 -6.100064)
			(size 0.762 0.762)
			(drill 0.359918)
			(layers "*.Cu" "*.Mask")
			(remove_unused_layers no)
			(net "GND")
			(clearance 0.1651)
			(thermal_gap 0.1651)
		)
		(pad "GND108" thru_hole circle
			(at 53.999892 -9.700006)
			(size 0.762 0.762)
			(drill 0.359918)
			(layers "*.Cu" "*.Mask")
			(remove_unused_layers no)
			(net "GND")
			(clearance 0.1651)
			(thermal_gap 0.1651)
		)
		(pad "GND109" thru_hole circle
			(at 55.79999 2.29997)
			(size 0.762 0.762)
			(drill 0.359918)
			(layers "*.Cu" "*.Mask")
			(remove_unused_layers no)
			(net "GND")
			(clearance 0.1651)
			(thermal_gap 0.1651)
		)
		(pad "GND110" thru_hole circle
			(at 55.79999 -1.299972)
			(size 0.762 0.762)
			(drill 0.359918)
			(layers "*.Cu" "*.Mask")
			(remove_unused_layers no)
			(net "GND")
			(clearance 0.1651)
			(thermal_gap 0.1651)
		)
		(pad "GND111" thru_hole circle
			(at 55.79999 -4.899914)
			(size 0.762 0.762)
			(drill 0.359918)
			(layers "*.Cu" "*.Mask")
			(remove_unused_layers no)
			(net "GND")
			(clearance 0.1651)
			(thermal_gap 0.1651)
		)
		(pad "GND112" thru_hole circle
			(at 55.79999 -8.50011)
			(size 0.762 0.762)
			(drill 0.359918)
			(layers "*.Cu" "*.Mask")
			(remove_unused_layers no)
			(net "GND")
			(clearance 0.1651)
			(thermal_gap 0.1651)
		)
		(pad "GND113" thru_hole circle
			(at 57.600088 -2.500122)
			(size 0.762 0.762)
			(drill 0.359918)
			(layers "*.Cu" "*.Mask")
			(remove_unused_layers no)
			(net "GND")
			(clearance 0.1651)
			(thermal_gap 0.1651)
		)
		(pad "GND114" thru_hole circle
			(at 57.600088 -6.100064)
			(size 0.762 0.762)
			(drill 0.359918)
			(layers "*.Cu" "*.Mask")
			(remove_unused_layers no)
			(net "GND")
			(clearance 0.1651)
			(thermal_gap 0.1651)
		)
		(pad "GND115" thru_hole circle
			(at 57.600088 -9.700006)
			(size 0.762 0.762)
			(drill 0.359918)
			(layers "*.Cu" "*.Mask")
			(remove_unused_layers no)
			(net "GND")
			(clearance 0.1651)
			(thermal_gap 0.1651)
		)
		(pad "GND116" thru_hole circle
			(at 59.399932 2.29997)
			(size 0.762 0.762)
			(drill 0.359918)
			(layers "*.Cu" "*.Mask")
			(remove_unused_layers no)
			(net "GND")
			(clearance 0.1651)
			(thermal_gap 0.1651)
		)
		(pad "GND117" thru_hole circle
			(at 59.399932 -1.299972)
			(size 0.762 0.762)
			(drill 0.359918)
			(layers "*.Cu" "*.Mask")
			(remove_unused_layers no)
			(net "GND")
			(clearance 0.1651)
			(thermal_gap 0.1651)
		)
		(pad "GND118" thru_hole circle
			(at 59.399932 -4.899914)
			(size 0.762 0.762)
			(drill 0.359918)
			(layers "*.Cu" "*.Mask")
			(remove_unused_layers no)
			(net "GND")
			(clearance 0.1651)
			(thermal_gap 0.1651)
		)
		(pad "GND119" thru_hole circle
			(at 59.399932 -8.50011)
			(size 0.762 0.762)
			(drill 0.359918)
			(layers "*.Cu" "*.Mask")
			(remove_unused_layers no)
			(net "GND")
			(clearance 0.1651)
			(thermal_gap 0.1651)
		)
		(pad "GND120" thru_hole circle
			(at 61.20003 -2.500122)
			(size 0.762 0.762)
			(drill 0.359918)
			(layers "*.Cu" "*.Mask")
			(remove_unused_layers no)
			(net "GND")
			(clearance 0.1651)
			(thermal_gap 0.1651)
		)
		(pad "GND121" thru_hole circle
			(at 61.20003 -6.100064)
			(size 0.762 0.762)
			(drill 0.359918)
			(layers "*.Cu" "*.Mask")
			(remove_unused_layers no)
			(net "GND")
			(clearance 0.1651)
			(thermal_gap 0.1651)
		)
		(pad "GND122" thru_hole circle
			(at 61.20003 -9.700006)
			(size 0.762 0.762)
			(drill 0.359918)
			(layers "*.Cu" "*.Mask")
			(remove_unused_layers no)
			(net "GND")
			(clearance 0.1651)
			(thermal_gap 0.1651)
		)
		(pad "GND123" thru_hole circle
			(at 62.999874 2.29997)
			(size 0.762 0.762)
			(drill 0.359918)
			(layers "*.Cu" "*.Mask")
			(remove_unused_layers no)
			(net "GND")
			(clearance 0.1651)
			(thermal_gap 0.1651)
		)
		(pad "GND124" thru_hole circle
			(at 62.999874 -1.299972)
			(size 0.762 0.762)
			(drill 0.359918)
			(layers "*.Cu" "*.Mask")
			(remove_unused_layers no)
			(net "GND")
			(clearance 0.1651)
			(thermal_gap 0.1651)
		)
		(pad "GND125" thru_hole circle
			(at 62.999874 -4.899914)
			(size 0.762 0.762)
			(drill 0.359918)
			(layers "*.Cu" "*.Mask")
			(remove_unused_layers no)
			(net "GND")
			(clearance 0.1651)
			(thermal_gap 0.1651)
		)
		(pad "GND126" thru_hole circle
			(at 62.999874 -8.50011)
			(size 0.762 0.762)
			(drill 0.359918)
			(layers "*.Cu" "*.Mask")
			(remove_unused_layers no)
			(net "GND")
			(clearance 0.1651)
			(thermal_gap 0.1651)
		)
	)
)
